# T6G (Grand Teton) — schematic netlist excerpt (pin names and nets, part order shuffled) for the footprints in the layout excerpt that follows; sources: Cadence DE-HDL packaged netlist, KiCad conversion of 04192023_DAF0TMB3IC0_F0TG_MB_C_brd_V02_OCP.brd

PR346  Q_RES  8.87K 1% EMPTY  pkg 0402LF  page 195 : A = GND ; B = PVDDCR_CPU0_P0_LSET3
R911  Q_RES  4.7K 5% EMPTY  pkg 0201LF  page 353 : A = P1V8_CPU1_RT_1D ; B = RST_RT_CPU1_P3_RESET_R_N
R885  Q_RES  4.7K 5% CHIP  pkg 0201LF  page 342 : A = P1V8_CPU1_RT_1D ; B = MODE_RT_CPU1_P2
R907  Q_RES  10K 1% CHIP  pkg 0201LF  page 353 : A = RST_RT_CPU1_P3_PERST_R_N ; B = GND
C6632  Q_CAP_DIFFBUS  DIFF BUS_0.22UF 6.3V 20% X6S  pkg C0201  page 319 : \1\ = P5E_CPU1_P0_TX_BUF_C_DN<1> ; \2\ = P5E_CPU1_P0_TX_BUF_DN<1>

(kicad_pcb
	(version 20260206)
	(generator "pcbnew")
	(generator_version "10.0")
	(general
		(thickness 1.6)
		(legacy_teardrops no)
	)
	(paper "A4")
	(title_block
		(title "04192023_DAF0TMB3IC0_F0TG_MB_C_brd_V02_OCP.brd")
		(comment 1 "Grand Teton / footprints 3990-3994 of 8354")
	)
	(layers
		(0 "F.Cu" signal "TOP")
		(4 "In1.Cu" signal "GND")
		(6 "In2.Cu" signal "IN1")
		(8 "In3.Cu" signal "GND1")
		(10 "In4.Cu" signal "IN2")
		(12 "In5.Cu" signal "GND2")
		(14 "In6.Cu" signal "IN3")
		(16 "In7.Cu" signal "GND3")
		(18 "In8.Cu" signal "VCC")
		(20 "In9.Cu" signal "VCC1")
		(22 "In10.Cu" signal "GND4")
		(24 "In11.Cu" signal "IN4")
		(26 "In12.Cu" signal "GND5")
		(28 "In13.Cu" signal "IN5")
		(30 "In14.Cu" signal "GND6")
		(32 "In15.Cu" signal "IN6")
		(34 "In16.Cu" signal "GND7")
		(2 "B.Cu" signal "BOTTOM")
		(9 "F.Adhes" user "F.Adhesive")
		(11 "B.Adhes" user "B.Adhesive")
		(13 "F.Paste" user "Package Geometry/Pastemask Top")
		(15 "B.Paste" user "Package Geometry/Pastemask Bottom")
		(5 "F.SilkS" user "Ref Des/Silkscreen Top")
		(7 "B.SilkS" user "Ref Des/Silkscreen Bottom")
		(1 "F.Mask" user "Board Geometry/Soldermask Top")
		(3 "B.Mask" user "Board Geometry/Soldermask Bottom")
		(17 "Dwgs.User" user "User.Drawings")
		(19 "Cmts.User" user "User.Comments")
		(21 "Eco1.User" user "User.Eco1")
		(23 "Eco2.User" user "User.Eco2")
		(25 "Edge.Cuts" user "Board Geometry/Outline")
		(27 "Margin" user)
		(31 "F.CrtYd" user "Package Geometry/Place Bound Top")
		(29 "B.CrtYd" user "Package Geometry/Place Bound Bottom")
		(35 "F.Fab" user "Ref Des/Assembly Top")
		(33 "B.Fab" user "Ref Des/Assembly Bottom")
	)
	(footprint ""
		(layer "F.Cu")
		(at 112.53216 -395.441932 -90)
		(property "Reference" "R911"
			(at 0 0 270)
			(layer "F.SilkS")
			(hide yes)
			(effects
				(font
					(size 1.27 1.27)
				)
			)
		)
		(property "Value" ""
			(at 0 0 270)
			(layer "F.Fab")
			(effects
				(font
					(size 1.27 1.27)
				)
			)
		)
		(duplicate_pad_numbers_are_jumpers no)
		(fp_line
			(start -0.32512 0.175006)
			(end -0.32512 -0.175006)
			(stroke
				(width 0.1)
				(type default)
			)
			(layer "F.Fab")
		)
		(fp_line
			(start 0.32512 0.175006)
			(end -0.32512 0.175006)
			(stroke
				(width 0.1)
				(type default)
			)
			(layer "F.Fab")
		)
		(fp_line
			(start -0.32512 -0.175006)
			(end 0.32512 -0.175006)
			(stroke
				(width 0.1)
				(type default)
			)
			(layer "F.Fab")
		)
		(fp_line
			(start 0.32512 -0.175006)
			(end 0.32512 0.175006)
			(stroke
				(width 0.1)
				(type default)
			)
			(layer "F.Fab")
		)
		(pad "1" smd rect
			(at -0.2667 0 270)
			(size 0.3048 0.381)
			(layers "F.Cu" "F.Mask" "F.Paste")
			(net "P1V8_CPU1_RT_1D")
		)
		(pad "2" smd rect
			(at 0.2667 0 90)
			(size 0.3048 0.381)
			(layers "F.Cu" "F.Mask" "F.Paste")
			(net "RST_RT_CPU1_P3_RESET_R_N")
		)
	)
	(footprint ""
		(layer "F.Cu")
		(at 135.02132 -394.35278 -90)
		(property "Reference" "R907"
			(at 0 0 270)
			(layer "F.SilkS")
			(hide yes)
			(effects
				(font
					(size 1.27 1.27)
				)
			)
		)
		(property "Value" ""
			(at 0 0 270)
			(layer "F.Fab")
			(effects
				(font
					(size 1.27 1.27)
				)
			)
		)
		(duplicate_pad_numbers_are_jumpers no)
		(fp_line
			(start -0.32512 0.175006)
			(end -0.32512 -0.175006)
			(stroke
				(width 0.1)
				(type default)
			)
			(layer "F.Fab")
		)
		(fp_line
			(start 0.32512 0.175006)
			(end -0.32512 0.175006)
			(stroke
				(width 0.1)
				(type default)
			)
			(layer "F.Fab")
		)
		(fp_line
			(start -0.32512 -0.175006)
			(end 0.32512 -0.175006)
			(stroke
				(width 0.1)
				(type default)
			)
			(layer "F.Fab")
		)
		(fp_line
			(start 0.32512 -0.175006)
			(end 0.32512 0.175006)
			(stroke
				(width 0.1)
				(type default)
			)
			(layer "F.Fab")
		)
		(pad "1" smd rect
			(at -0.2667 0 270)
			(size 0.3048 0.381)
			(layers "F.Cu" "F.Mask" "F.Paste")
			(net "RST_RT_CPU1_P3_PERST_R_N")
		)
		(pad "2" smd rect
			(at 0.2667 0 90)
			(size 0.3048 0.381)
			(layers "F.Cu" "F.Mask" "F.Paste")
			(net "GND")
		)
	)
	(footprint ""
		(layer "F.Cu")
		(at 50.832004 -408.517344 -90)
		(property "Reference" "C6632"
			(at 0 0 270)
			(layer "F.SilkS")
			(hide yes)
			(effects
				(font
					(size 1.27 1.27)
				)
			)
		)
		(property "Value" ""
			(at 0 0 270)
			(layer "F.Fab")
			(effects
				(font
					(size 1.27 1.27)
				)
			)
		)
		(duplicate_pad_numbers_are_jumpers no)
		(fp_line
			(start -0.299974 0.150114)
			(end -0.299974 -0.150114)
			(stroke
				(width 0.1)
				(type default)
			)
			(layer "F.Fab")
		)
		(fp_line
			(start 0.299974 0.150114)
			(end -0.299974 0.150114)
			(stroke
				(width 0.1)
				(type default)
			)
			(layer "F.Fab")
		)
		(fp_line
			(start -0.299974 -0.150114)
			(end 0.299974 -0.150114)
			(stroke
				(width 0.1)
				(type default)
			)
			(layer "F.Fab")
		)
		(fp_line
			(start 0.299974 -0.150114)
			(end 0.299974 0.150114)
			(stroke
				(width 0.1)
				(type default)
			)
			(layer "F.Fab")
		)
		(pad "1" smd rect
			(at -0.2667 0 270)
			(size 0.3048 0.381)
			(layers "F.Cu" "F.Mask" "F.Paste")
			(net "P5E_CPU1_P0_TX_BUF_C_DN<1>")
		)
		(pad "2" smd rect
			(at 0.2667 0 270)
			(size 0.3048 0.381)
			(layers "F.Cu" "F.Mask" "F.Paste")
			(net "P5E_CPU1_P0_TX_BUF_DN<1>")
		)
	)
	(footprint ""
		(layer "F.Cu")
		(at 382.382522 -177.532284)
		(property "Reference" "PR346"
			(at 0 0 0)
			(layer "F.SilkS")
			(hide yes)
			(effects
				(font
					(size 1.27 1.27)
				)
			)
		)
		(property "Value" ""
			(at 0 0 0)
			(layer "F.Fab")
			(effects
				(font
					(size 1.27 1.27)
				)
			)
		)
		(duplicate_pad_numbers_are_jumpers no)
		(fp_line
			(start -0.7874 -0.4064)
			(end 0.7874 -0.4064)
			(stroke
				(width 0.1524)
				(type default)
			)
			(layer "F.SilkS")
		)
		(fp_line
			(start -0.7874 0.4064)
			(end -0.7874 -0.4064)
			(stroke
				(width 0.1524)
				(type default)
			)
			(layer "F.SilkS")
		)
		(fp_line
			(start 0.7874 -0.4064)
			(end 0.7874 0.4064)
			(stroke
				(width 0.1524)
				(type default)
			)
			(layer "F.SilkS")
		)
		(fp_line
			(start 0.7874 0.4064)
			(end -0.7874 0.4064)
			(stroke
				(width 0.1524)
				(type default)
			)
			(layer "F.SilkS")
		)
		(fp_line
			(start -0.67945 -0.305054)
			(end -0.12065 -0.305054)
			(stroke
				(width 0.1)
				(type default)
			)
			(layer "F.Fab")
		)
		(fp_line
			(start -0.67945 0.3048)
			(end -0.67945 -0.305054)
			(stroke
				(width 0.1)
				(type default)
			)
			(layer "F.Fab")
		)
		(fp_line
			(start -0.12065 -0.305054)
			(end -0.12065 -0.2794)
			(stroke
				(width 0.1)
				(type default)
			)
			(layer "F.Fab")
		)
		(fp_line
			(start -0.12065 -0.2794)
			(end 0.12065 -0.2794)
			(stroke
				(width 0.1)
				(type default)
			)
			(layer "F.Fab")
		)
		(fp_line
			(start -0.12065 0.2794)
			(end -0.12065 0.3048)
			(stroke
				(width 0.1)
				(type default)
			)
			(layer "F.Fab")
		)
		(fp_line
			(start -0.12065 0.3048)
			(end -0.67945 0.3048)
			(stroke
				(width 0.1)
				(type default)
			)
			(layer "F.Fab")
		)
		(fp_line
			(start 0.120396 0.2794)
			(end -0.12065 0.2794)
			(stroke
				(width 0.1)
				(type default)
			)
			(layer "F.Fab")
		)
		(fp_line
			(start 0.120396 0.3048)
			(end 0.120396 0.2794)
			(stroke
				(width 0.1)
				(type default)
			)
			(layer "F.Fab")
		)
		(fp_line
			(start 0.12065 -0.3048)
			(end 0.67945 -0.3048)
			(stroke
				(width 0.1)
				(type default)
			)
			(layer "F.Fab")
		)
		(fp_line
			(start 0.12065 -0.2794)
			(end 0.12065 -0.3048)
			(stroke
				(width 0.1)
				(type default)
			)
			(layer "F.Fab")
		)
		(fp_line
			(start 0.67945 -0.3048)
			(end 0.67945 0.3048)
			(stroke
				(width 0.1)
				(type default)
			)
			(layer "F.Fab")
		)
		(fp_line
			(start 0.67945 0.3048)
			(end 0.120396 0.3048)
			(stroke
				(width 0.1)
				(type default)
			)
			(layer "F.Fab")
		)
		(pad "1" smd circle
			(at -0.40005 0)
			(size 0 0)
			(layers "F.Cu" "F.Mask" "F.Paste")
			(net "GND")
		)
		(pad "2" smd circle
			(at 0.40005 0)
			(size 0 0)
			(layers "F.Cu" "F.Mask" "F.Paste")
			(net "PVDDCR_CPU0_P0_LSET3")
		)
	)
	(footprint ""
		(layer "F.Cu")
		(at 145.128488 -395.436852 -90)
		(property "Reference" "R885"
			(at 0 0 270)
			(layer "F.SilkS")
			(hide yes)
			(effects
				(font
					(size 1.27 1.27)
				)
			)
		)
		(property "Value" ""
			(at 0 0 270)
			(layer "F.Fab")
			(effects
				(font
					(size 1.27 1.27)
				)
			)
		)
		(duplicate_pad_numbers_are_jumpers no)
		(fp_line
			(start -0.32512 0.175006)
			(end -0.32512 -0.175006)
			(stroke
				(width 0.1)
				(type default)
			)
			(layer "F.Fab")
		)
		(fp_line
			(start 0.32512 0.175006)
			(end -0.32512 0.175006)
			(stroke
				(width 0.1)
				(type default)
			)
			(layer "F.Fab")
		)
		(fp_line
			(start -0.32512 -0.175006)
			(end 0.32512 -0.175006)
			(stroke
				(width 0.1)
				(type default)
			)
			(layer "F.Fab")
		)
		(fp_line
			(start 0.32512 -0.175006)
			(end 0.32512 0.175006)
			(stroke
				(width 0.1)
				(type default)
			)
			(layer "F.Fab")
		)
		(pad "1" smd rect
			(at -0.2667 0 270)
			(size 0.3048 0.381)
			(layers "F.Cu" "F.Mask" "F.Paste")
			(net "P1V8_CPU1_RT_1D")
		)
		(pad "2" smd rect
			(at 0.2667 0 90)
			(size 0.3048 0.381)
			(layers "F.Cu" "F.Mask" "F.Paste")
			(net "MODE_RT_CPU1_P2")
		)
	)
)
